# T6G (Grand Teton) — schematic netlist excerpt (pin names and nets, part order shuffled) for the footprints in the layout excerpt that follows; sources: Cadence DE-HDL packaged netlist, KiCad conversion of 04192023_DAF0TMB3IC0_F0TG_MB_C_brd_V02_OCP.brd

R1645  Q_RES  22 1% CHIP  pkg 0402LF  page 173 : A = JTAG_P1_R_DBREQ_N ; B = JTAG_CPU1_DBREQ_N
C17  Q_CAP  0.1UF 25V 10% X7R  pkg 0402  page 125 : A = GPU_3V3IO_RSVD5_FFU_ISO ; B = GND

(kicad_pcb
	(version 20260206)
	(generator "pcbnew")
	(generator_version "10.0")
	(general
		(thickness 1.6)
		(legacy_teardrops no)
	)
	(paper "A4")
	(title_block
		(title "04192023_DAF0TMB3IC0_F0TG_MB_C_brd_V02_OCP.brd")
		(comment 1 "Grand Teton / footprints 3919-3920 of 8354")
	)
	(layers
		(0 "F.Cu" signal "TOP")
		(4 "In1.Cu" signal "GND")
		(6 "In2.Cu" signal "IN1")
		(8 "In3.Cu" signal "GND1")
		(10 "In4.Cu" signal "IN2")
		(12 "In5.Cu" signal "GND2")
		(14 "In6.Cu" signal "IN3")
		(16 "In7.Cu" signal "GND3")
		(18 "In8.Cu" signal "VCC")
		(20 "In9.Cu" signal "VCC1")
		(22 "In10.Cu" signal "GND4")
		(24 "In11.Cu" signal "IN4")
		(26 "In12.Cu" signal "GND5")
		(28 "In13.Cu" signal "IN5")
		(30 "In14.Cu" signal "GND6")
		(32 "In15.Cu" signal "IN6")
		(34 "In16.Cu" signal "GND7")
		(2 "B.Cu" signal "BOTTOM")
		(9 "F.Adhes" user "F.Adhesive")
		(11 "B.Adhes" user "B.Adhesive")
		(13 "F.Paste" user "Package Geometry/Pastemask Top")
		(15 "B.Paste" user "Package Geometry/Pastemask Bottom")
		(5 "F.SilkS" user "Ref Des/Silkscreen Top")
		(7 "B.SilkS" user "Ref Des/Silkscreen Bottom")
		(1 "F.Mask" user "Board Geometry/Soldermask Top")
		(3 "B.Mask" user "Board Geometry/Soldermask Bottom")
		(17 "Dwgs.User" user "User.Drawings")
		(19 "Cmts.User" user "User.Comments")
		(21 "Eco1.User" user "User.Eco1")
		(23 "Eco2.User" user "User.Eco2")
		(25 "Edge.Cuts" user "Board Geometry/Outline")
		(27 "Margin" user)
		(31 "F.CrtYd" user "Package Geometry/Place Bound Top")
		(29 "B.CrtYd" user "Package Geometry/Place Bound Bottom")
		(35 "F.Fab" user "Ref Des/Assembly Top")
		(33 "B.Fab" user "Ref Des/Assembly Bottom")
	)
	(footprint ""
		(layer "F.Cu")
		(at 307.404516 -439.276744 90)
		(property "Reference" "C17"
			(at 0 0 90)
			(layer "F.SilkS")
			(hide yes)
			(effects
				(font
					(size 1.27 1.27)
				)
			)
		)
		(property "Value" ""
			(at 0 0 90)
			(layer "F.Fab")
			(effects
				(font
					(size 1.27 1.27)
				)
			)
		)
		(duplicate_pad_numbers_are_jumpers no)
		(fp_line
			(start 0.7874 -0.4064)
			(end 0.7874 0.4064)
			(stroke
				(width 0.1524)
				(type default)
			)
			(layer "F.SilkS")
		)
		(fp_line
			(start -0.7874 -0.4064)
			(end 0.7874 -0.4064)
			(stroke
				(width 0.1524)
				(type default)
			)
			(layer "F.SilkS")
		)
		(fp_line
			(start 0.7874 0.4064)
			(end -0.7874 0.4064)
			(stroke
				(width 0.1524)
				(type default)
			)
			(layer "F.SilkS")
		)
		(fp_line
			(start -0.7874 0.4064)
			(end -0.7874 -0.4064)
			(stroke
				(width 0.1524)
				(type default)
			)
			(layer "F.SilkS")
		)
		(fp_line
			(start -0.12065 -0.305054)
			(end -0.12065 -0.2794)
			(stroke
				(width 0.1)
				(type default)
			)
			(layer "F.Fab")
		)
		(fp_line
			(start -0.67945 -0.305054)
			(end -0.12065 -0.305054)
			(stroke
				(width 0.1)
				(type default)
			)
			(layer "F.Fab")
		)
		(fp_line
			(start 0.67945 -0.3048)
			(end 0.67945 0.3048)
			(stroke
				(width 0.1)
				(type default)
			)
			(layer "F.Fab")
		)
		(fp_line
			(start 0.12065 -0.3048)
			(end 0.67945 -0.3048)
			(stroke
				(width 0.1)
				(type default)
			)
			(layer "F.Fab")
		)
		(fp_line
			(start 0.12065 -0.2794)
			(end 0.12065 -0.3048)
			(stroke
				(width 0.1)
				(type default)
			)
			(layer "F.Fab")
		)
		(fp_line
			(start -0.12065 -0.2794)
			(end 0.12065 -0.2794)
			(stroke
				(width 0.1)
				(type default)
			)
			(layer "F.Fab")
		)
		(fp_line
			(start 0.120396 0.2794)
			(end -0.12065 0.2794)
			(stroke
				(width 0.1)
				(type default)
			)
			(layer "F.Fab")
		)
		(fp_line
			(start -0.12065 0.2794)
			(end -0.12065 0.3048)
			(stroke
				(width 0.1)
				(type default)
			)
			(layer "F.Fab")
		)
		(fp_line
			(start 0.67945 0.3048)
			(end 0.120396 0.3048)
			(stroke
				(width 0.1)
				(type default)
			)
			(layer "F.Fab")
		)
		(fp_line
			(start 0.120396 0.3048)
			(end 0.120396 0.2794)
			(stroke
				(width 0.1)
				(type default)
			)
			(layer "F.Fab")
		)
		(fp_line
			(start -0.12065 0.3048)
			(end -0.67945 0.3048)
			(stroke
				(width 0.1)
				(type default)
			)
			(layer "F.Fab")
		)
		(fp_line
			(start -0.67945 0.3048)
			(end -0.67945 -0.305054)
			(stroke
				(width 0.1)
				(type default)
			)
			(layer "F.Fab")
		)
		(pad "1" smd circle
			(at -0.40005 0 90)
			(size 0 0)
			(layers "F.Cu" "F.Mask" "F.Paste")
			(net "GPU_3V3IO_RSVD5_FFU_ISO")
		)
		(pad "2" smd circle
			(at 0.40005 0 90)
			(size 0 0)
			(layers "F.Cu" "F.Mask" "F.Paste")
			(net "GND")
		)
	)
	(footprint ""
		(layer "F.Cu")
		(at 275.14169 -99.371404 180)
		(property "Reference" "R1645"
			(at 0 0 180)
			(layer "F.SilkS")
			(hide yes)
			(effects
				(font
					(size 1.27 1.27)
				)
			)
		)
		(property "Value" ""
			(at 0 0 180)
			(layer "F.Fab")
			(effects
				(font
					(size 1.27 1.27)
				)
			)
		)
		(duplicate_pad_numbers_are_jumpers no)
		(fp_line
			(start 0.7874 0.4064)
			(end -0.7874 0.4064)
			(stroke
				(width 0.1524)
				(type default)
			)
			(layer "F.SilkS")
		)
		(fp_line
			(start 0.7874 -0.4064)
			(end 0.7874 0.4064)
			(stroke
				(width 0.1524)
				(type default)
			)
			(layer "F.SilkS")
		)
		(fp_line
			(start -0.7874 0.4064)
			(end -0.7874 -0.4064)
			(stroke
				(width 0.1524)
				(type default)
			)
			(layer "F.SilkS")
		)
		(fp_line
			(start -0.7874 -0.4064)
			(end 0.7874 -0.4064)
			(stroke
				(width 0.1524)
				(type default)
			)
			(layer "F.SilkS")
		)
		(fp_line
			(start 0.67945 0.3048)
			(end 0.120396 0.3048)
			(stroke
				(width 0.1)
				(type default)
			)
			(layer "F.Fab")
		)
		(fp_line
			(start 0.67945 -0.3048)
			(end 0.67945 0.3048)
			(stroke
				(width 0.1)
				(type default)
			)
			(layer "F.Fab")
		)
		(fp_line
			(start 0.12065 -0.2794)
			(end 0.12065 -0.3048)
			(stroke
				(width 0.1)
				(type default)
			)
			(layer "F.Fab")
		)
		(fp_line
			(start 0.12065 -0.3048)
			(end 0.67945 -0.3048)
			(stroke
				(width 0.1)
				(type default)
			)
			(layer "F.Fab")
		)
		(fp_line
			(start 0.120396 0.3048)
			(end 0.120396 0.2794)
			(stroke
				(width 0.1)
				(type default)
			)
			(layer "F.Fab")
		)
		(fp_line
			(start 0.120396 0.2794)
			(end -0.12065 0.2794)
			(stroke
				(width 0.1)
				(type default)
			)
			(layer "F.Fab")
		)
		(fp_line
			(start -0.12065 0.3048)
			(end -0.67945 0.3048)
			(stroke
				(width 0.1)
				(type default)
			)
			(layer "F.Fab")
		)
		(fp_line
			(start -0.12065 0.2794)
			(end -0.12065 0.3048)
			(stroke
				(width 0.1)
				(type default)
			)
			(layer "F.Fab")
		)
		(fp_line
			(start -0.12065 -0.2794)
			(end 0.12065 -0.2794)
			(stroke
				(width 0.1)
				(type default)
			)
			(layer "F.Fab")
		)
		(fp_line
			(start -0.12065 -0.305054)
			(end -0.12065 -0.2794)
			(stroke
				(width 0.1)
				(type default)
			)
			(layer "F.Fab")
		)
		(fp_line
			(start -0.67945 0.3048)
			(end -0.67945 -0.305054)
			(stroke
				(width 0.1)
				(type default)
			)
			(layer "F.Fab")
		)
		(fp_line
			(start -0.67945 -0.305054)
			(end -0.12065 -0.305054)
			(stroke
				(width 0.1)
				(type default)
			)
			(layer "F.Fab")
		)
		(pad "1" smd circle
			(at -0.40005 0 180)
			(size 0 0)
			(layers "F.Cu" "F.Mask" "F.Paste")
			(net "JTAG_P1_R_DBREQ_N")
		)
		(pad "2" smd circle
			(at 0.40005 0 180)
			(size 0 0)
			(layers "F.Cu" "F.Mask" "F.Paste")
			(net "JTAG_CPU1_DBREQ_N")
		)
	)
)
